# BASEBOARD_FAB2 (Tioga Pass) — schematic netlist excerpt (pin names and nets, part order shuffled) for the footprints in the layout excerpt that follows; sources: Cadence DE-HDL packaged netlist, KiCad conversion of Wiwynn_Tioga_Pass_MB.brd

R3P54  RES  3.32K 1% EMPTY  pkg 0402  page 156 : A = P3V3_STBY ; B = FM_CPU0_SM_WP
C8F16  CAP_A  0.1UF 16V 10% X7R  pkg 0402V  page 156 : A = P3V3_STBY ; B = GND
R3R5  RES  665 1.0% CHIP  pkg 0402  page 99 : A = PVPP_DEF ; B = SMB_DDR_DEF_VPP_SCL_R

(kicad_pcb
	(version 20260206)
	(generator "pcbnew")
	(generator_version "10.0")
	(general
		(thickness 1.6)
		(legacy_teardrops no)
	)
	(paper "A4")
	(title_block
		(title "Wiwynn_Tioga_Pass_MB.brd")
		(comment 1 "Tioga Pass / footprints 3673-3675 of 4770")
	)
	(layers
		(0 "F.Cu" signal "TOP")
		(4 "In1.Cu" signal "L2GND")
		(6 "In2.Cu" signal "L3")
		(8 "In3.Cu" signal "L4GND")
		(10 "In4.Cu" signal "L5")
		(12 "In5.Cu" signal "L6GND")
		(14 "In6.Cu" signal "L7VCC")
		(16 "In7.Cu" signal "L8VCC")
		(18 "In8.Cu" signal "L9GND")
		(20 "In9.Cu" signal "L10")
		(22 "In10.Cu" signal "L11GND")
		(24 "In11.Cu" signal "L12")
		(26 "In12.Cu" signal "L13GND")
		(2 "B.Cu" signal "BOTTOM")
		(9 "F.Adhes" user "F.Adhesive")
		(11 "B.Adhes" user "B.Adhesive")
		(13 "F.Paste" user "Package Geometry/Pastemask Top")
		(15 "B.Paste" user "Package Geometry/Pastemask Bottom")
		(5 "F.SilkS" user "Ref Des/Silkscreen Top")
		(7 "B.SilkS" user "Ref Des/Silkscreen Bottom")
		(1 "F.Mask" user "Board Geometry/Soldermask Top")
		(3 "B.Mask" user "Board Geometry/Soldermask Bottom")
		(17 "Dwgs.User" user "User.Drawings")
		(19 "Cmts.User" user "User.Comments")
		(21 "Eco1.User" user "User.Eco1")
		(23 "Eco2.User" user "User.Eco2")
		(25 "Edge.Cuts" user "Board Geometry/Outline")
		(27 "Margin" user)
		(31 "F.CrtYd" user "Package Geometry/Place Bound Top")
		(29 "B.CrtYd" user "Package Geometry/Place Bound Bottom")
		(35 "F.Fab" user "Ref Des/Assembly Top")
		(33 "B.Fab" user "Ref Des/Assembly Bottom")
	)
	(footprint ""
		(layer "B.Cu")
		(at 318.61506 -126.31674)
		(property "Reference" "R3R5"
			(at 0 0 0)
			(layer "B.SilkS")
			(hide yes)
			(effects
				(font
					(size 1.27 1.27)
				)
				(justify mirror)
			)
		)
		(property "Value" ""
			(at 0 0 0)
			(layer "B.Fab")
			(effects
				(font
					(size 1.27 1.27)
				)
				(justify mirror)
			)
		)
		(duplicate_pad_numbers_are_jumpers no)
		(fp_poly
			(pts
				(xy 0.2794 -0.1016) (xy -0.2794 -0.1016) (xy -0.2794 0.9906) (xy 0.2794 0.9906)
			)
			(stroke
				(width 0)
				(type default)
			)
			(fill no)
			(layer "B.CrtYd")
		)
		(fp_line
			(start -0.2794 -0.1016)
			(end 0.2794 -0.1016)
			(stroke
				(width 0.1)
				(type default)
			)
			(layer "B.Fab")
		)
		(fp_line
			(start -0.2794 0.9906)
			(end -0.2794 -0.1016)
			(stroke
				(width 0.1)
				(type default)
			)
			(layer "B.Fab")
		)
		(fp_line
			(start 0.2794 -0.1016)
			(end 0.2794 0.9906)
			(stroke
				(width 0.1)
				(type default)
			)
			(layer "B.Fab")
		)
		(fp_line
			(start 0.2794 0.9906)
			(end -0.2794 0.9906)
			(stroke
				(width 0.1)
				(type default)
			)
			(layer "B.Fab")
		)
		(pad "1" smd rect
			(at 0 0 180)
			(size 0.508 0.508)
			(layers "B.Cu" "B.Mask" "B.Paste")
			(net "PVPP_DEF")
		)
		(pad "2" smd rect
			(at 0 0.889 180)
			(size 0.508 0.508)
			(layers "B.Cu" "B.Mask" "B.Paste")
			(net "SMB_DDR_DEF_VPP_SCL_R")
		)
		(zone
			(layer "B.Cu")
			(hatch none 0.5)
			(connect_pads
				(clearance 0)
			)
			(min_thickness 0.25)
			(keepout
				(tracks allowed)
				(vias not_allowed)
				(pads allowed)
				(copperpour not_allowed)
				(footprints allowed)
			)
			(placement
				(enabled no)
				(sheetname "")
			)
			(fill
				(thermal_gap 0.5)
				(thermal_bridge_width 0.5)
				(island_removal_mode 0)
			)
			(polygon
				(pts
					(xy 318.86906 -126.06274) (xy 318.36106 -126.06274) (xy 318.36106 -125.68174) (xy 318.86906 -125.68174)
				)
			)
		)
		(zone
			(layer "B.Cu")
			(hatch none 0.5)
			(connect_pads
				(clearance 0)
			)
			(min_thickness 0.25)
			(keepout
				(tracks not_allowed)
				(vias allowed)
				(pads allowed)
				(copperpour not_allowed)
				(footprints allowed)
			)
			(placement
				(enabled no)
				(sheetname "")
			)
			(fill
				(thermal_gap 0.5)
				(thermal_bridge_width 0.5)
				(island_removal_mode 0)
			)
			(polygon
				(pts
					(xy 318.86906 -125.68174) (xy 318.36106 -125.68174) (xy 318.36106 -126.06274) (xy 318.86906 -126.06274)
				)
			)
		)
	)
	(footprint ""
		(layer "B.Cu")
		(at 337.1596 -85.70722)
		(property "Reference" "R3P54"
			(at 0 0 0)
			(layer "B.SilkS")
			(hide yes)
			(effects
				(font
					(size 1.27 1.27)
				)
				(justify mirror)
			)
		)
		(property "Value" ""
			(at 0 0 0)
			(layer "B.Fab")
			(effects
				(font
					(size 1.27 1.27)
				)
				(justify mirror)
			)
		)
		(duplicate_pad_numbers_are_jumpers no)
		(fp_poly
			(pts
				(xy 0.2794 -0.1016) (xy -0.2794 -0.1016) (xy -0.2794 0.9906) (xy 0.2794 0.9906)
			)
			(stroke
				(width 0)
				(type default)
			)
			(fill no)
			(layer "B.CrtYd")
		)
		(fp_line
			(start -0.2794 -0.1016)
			(end 0.2794 -0.1016)
			(stroke
				(width 0.1)
				(type default)
			)
			(layer "B.Fab")
		)
		(fp_line
			(start -0.2794 0.9906)
			(end -0.2794 -0.1016)
			(stroke
				(width 0.1)
				(type default)
			)
			(layer "B.Fab")
		)
		(fp_line
			(start 0.2794 -0.1016)
			(end 0.2794 0.9906)
			(stroke
				(width 0.1)
				(type default)
			)
			(layer "B.Fab")
		)
		(fp_line
			(start 0.2794 0.9906)
			(end -0.2794 0.9906)
			(stroke
				(width 0.1)
				(type default)
			)
			(layer "B.Fab")
		)
		(pad "1" smd rect
			(at 0 0 180)
			(size 0.508 0.508)
			(layers "B.Cu" "B.Mask" "B.Paste")
			(net "P3V3_STBY")
		)
		(pad "2" smd rect
			(at 0 0.889 180)
			(size 0.508 0.508)
			(layers "B.Cu" "B.Mask" "B.Paste")
			(net "FM_CPU0_SM_WP")
		)
		(zone
			(layer "B.Cu")
			(hatch none 0.5)
			(connect_pads
				(clearance 0)
			)
			(min_thickness 0.25)
			(keepout
				(tracks allowed)
				(vias not_allowed)
				(pads allowed)
				(copperpour not_allowed)
				(footprints allowed)
			)
			(placement
				(enabled no)
				(sheetname "")
			)
			(fill
				(thermal_gap 0.5)
				(thermal_bridge_width 0.5)
				(island_removal_mode 0)
			)
			(polygon
				(pts
					(xy 337.4136 -85.45322) (xy 336.9056 -85.45322) (xy 336.9056 -85.07222) (xy 337.4136 -85.07222)
				)
			)
		)
		(zone
			(layer "B.Cu")
			(hatch none 0.5)
			(connect_pads
				(clearance 0)
			)
			(min_thickness 0.25)
			(keepout
				(tracks not_allowed)
				(vias allowed)
				(pads allowed)
				(copperpour not_allowed)
				(footprints allowed)
			)
			(placement
				(enabled no)
				(sheetname "")
			)
			(fill
				(thermal_gap 0.5)
				(thermal_bridge_width 0.5)
				(island_removal_mode 0)
			)
			(polygon
				(pts
					(xy 337.4136 -85.07222) (xy 336.9056 -85.07222) (xy 336.9056 -85.45322) (xy 337.4136 -85.45322)
				)
			)
		)
	)
	(footprint ""
		(layer "B.Cu")
		(at 393.446 -27.686 -90)
		(property "Reference" "C8F16"
			(at 0 0 90)
			(layer "B.SilkS")
			(hide yes)
			(effects
				(font
					(size 1.27 1.27)
				)
				(justify mirror)
			)
		)
		(property "Value" ""
			(at 0 0 90)
			(layer "B.Fab")
			(effects
				(font
					(size 1.27 1.27)
				)
				(justify mirror)
			)
		)
		(duplicate_pad_numbers_are_jumpers no)
		(fp_poly
			(pts
				(xy -0.3048 -0.1016) (xy -0.3048 0.9906) (xy 0.3048 0.9906) (xy 0.3048 -0.1016)
			)
			(stroke
				(width 0)
				(type default)
			)
			(fill no)
			(layer "B.CrtYd")
		)
		(fp_line
			(start -0.3048 0.9906)
			(end -0.3048 -0.1016)
			(stroke
				(width 0.1)
				(type default)
			)
			(layer "B.Fab")
		)
		(fp_line
			(start 0.3048 0.9906)
			(end -0.3048 0.9906)
			(stroke
				(width 0.1)
				(type default)
			)
			(layer "B.Fab")
		)
		(fp_line
			(start -0.3048 -0.1016)
			(end 0.3048 -0.1016)
			(stroke
				(width 0.1)
				(type default)
			)
			(layer "B.Fab")
		)
		(fp_line
			(start 0.3048 -0.1016)
			(end 0.3048 0.9906)
			(stroke
				(width 0.1)
				(type default)
			)
			(layer "B.Fab")
		)
		(pad "1" smd rect
			(at 0 0 90)
			(size 0.508 0.508)
			(layers "B.Cu" "B.Mask" "B.Paste")
			(net "P3V3_STBY")
		)
		(pad "2" smd rect
			(at 0 0.889 90)
			(size 0.508 0.508)
			(layers "B.Cu" "B.Mask" "B.Paste")
			(net "GND")
		)
		(zone
			(layer "B.Cu")
			(hatch none 0.5)
			(connect_pads
				(clearance 0)
			)
			(min_thickness 0.25)
			(keepout
				(tracks not_allowed)
				(vias allowed)
				(pads allowed)
				(copperpour not_allowed)
				(footprints allowed)
			)
			(placement
				(enabled no)
				(sheetname "")
			)
			(fill
				(thermal_gap 0.5)
				(thermal_bridge_width 0.5)
				(island_removal_mode 0)
			)
			(polygon
				(pts
					(xy 392.811 -27.432) (xy 392.811 -27.94) (xy 393.192 -27.94) (xy 393.192 -27.432)
				)
			)
		)
		(zone
			(layer "B.Cu")
			(hatch none 0.5)
			(connect_pads
				(clearance 0)
			)
			(min_thickness 0.25)
			(keepout
				(tracks allowed)
				(vias not_allowed)
				(pads allowed)
				(copperpour not_allowed)
				(footprints allowed)
			)
			(placement
				(enabled no)
				(sheetname "")
			)
			(fill
				(thermal_gap 0.5)
				(thermal_bridge_width 0.5)
				(island_removal_mode 0)
			)
			(polygon
				(pts
					(xy 393.192 -27.432) (xy 393.192 -27.94) (xy 392.811 -27.94) (xy 392.811 -27.432)
				)
			)
		)
	)
)
